G04 ================== begin FILE IDENTIFICATION RECORD ==================*
G04 Layout Name:  12004-1.brd*
G04 Film Name:    BSMD*
G04 File Format:  Gerber RS274X*
G04 File Origin:  Cadence Allegro 16.2-S033*
G04 Origin Date:  Tue Oct 16 14:35:48 2012*
G04 *
G04 Layer:  VIA CLASS/PASTEMASK_BOTTOM*
G04 Layer:  PIN/PASTEMASK_BOTTOM*
G04 Layer:  PACKAGE GEOMETRY/PASTEMASK_BOTTOM*
G04 Layer:  DRAWING FORMAT/LAYER_PCB_STORY*
G04 Layer:  DRAWING FORMAT/LAYER_PAST_B*
G04 Layer:  BOARD GEOMETRY/PANEL_OUTLINE*
G04 *
G04 Offset:    (0.00 0.00)*
G04 Mirror:    No*
G04 Mode:      Positive*
G04 Rotation:  0*
G04 FullContactRelief:  No*
G04 UndefLineWidth:     6.00*
G04 ================== end FILE IDENTIFICATION RECORD ====================*
%FSLAX35Y35*MOIN*%
%IR0*IPPOS*OFA0.00000B0.00000*MIA0B0*SFA1.00000B1.00000*%
%AMMACRO16*
4,1,40,.011,.007,
.011,-.007,
.010939,-.007695,
.010759,-.008368,
.010464,-.009,
.010064,-.009571,
.009571,-.010064,
.009,-.010464,
.008368,-.010759,
.007695,-.010939,
.007,-.011,
-.007,-.011,
-.007695,-.010939,
-.008368,-.010759,
-.009,-.010464,
-.009571,-.010064,
-.010064,-.009571,
-.010464,-.009,
-.010759,-.008368,
-.010939,-.007695,
-.011,-.007,
-.011,.007,
-.010939,.007695,
-.010759,.008368,
-.010464,.009,
-.010064,.009571,
-.009571,.010064,
-.009,.010464,
-.008368,.010759,
-.007695,.010939,
-.007,.011,
.007,.011,
.007695,.010939,
.008368,.010759,
.009,.010464,
.009571,.010064,
.010064,.009571,
.010464,.009,
.010759,.008368,
.010939,.007695,
.011,.007,
0.0*
%
%ADD16MACRO16*%
%AMMACRO35*
4,1,40,-.017,-.013,
-.017,.013,
-.016939,.013695,
-.016759,.014368,
-.016464,.015,
-.016064,.015571,
-.015571,.016064,
-.015,.016464,
-.014368,.016759,
-.013695,.016939,
-.013,.017,
.013,.017,
.013695,.016939,
.014368,.016759,
.015,.016464,
.015571,.016064,
.016064,.015571,
.016464,.015,
.016759,.014368,
.016939,.013695,
.017,.013,
.017,-.013,
.016939,-.013695,
.016759,-.014368,
.016464,-.015,
.016064,-.015571,
.015571,-.016064,
.015,-.016464,
.014368,-.016759,
.013695,-.016939,
.013,-.017,
-.013,-.017,
-.013695,-.016939,
-.014368,-.016759,
-.015,-.016464,
-.015571,-.016064,
-.016064,-.015571,
-.016464,-.015,
-.016759,-.014368,
-.016939,-.013695,
-.017,-.013,
0.0*
%
%ADD35MACRO35*%
%AMMACRO24*
4,1,40,.013,-.017,
-.013,-.017,
-.013695,-.016939,
-.014368,-.016759,
-.015,-.016464,
-.015571,-.016064,
-.016064,-.015571,
-.016464,-.015,
-.016759,-.014368,
-.016939,-.013695,
-.017,-.013,
-.017,.013,
-.016939,.013695,
-.016759,.014368,
-.016464,.015,
-.016064,.015571,
-.015571,.016064,
-.015,.016464,
-.014368,.016759,
-.013695,.016939,
-.013,.017,
.013,.017,
.013695,.016939,
.014368,.016759,
.015,.016464,
.015571,.016064,
.016064,.015571,
.016464,.015,
.016759,.014368,
.016939,.013695,
.017,.013,
.017,-.013,
.016939,-.013695,
.016759,-.014368,
.016464,-.015,
.016064,-.015571,
.015571,-.016064,
.015,-.016464,
.014368,-.016759,
.013695,-.016939,
.013,-.017,
0.0*
%
%ADD24MACRO24*%
%ADD11R,.05X.05*%
%ADD50R,.081X.297*%
%AMMACRO27*
4,1,40,.007,-.011,
-.007,-.011,
-.007695,-.010939,
-.008368,-.010759,
-.009,-.010464,
-.009571,-.010064,
-.010064,-.009571,
-.010464,-.009,
-.010759,-.008368,
-.010939,-.007695,
-.011,-.007,
-.011,.007,
-.010939,.007695,
-.010759,.008368,
-.010464,.009,
-.010064,.009571,
-.009571,.010064,
-.009,.010464,
-.008368,.010759,
-.007695,.010939,
-.007,.011,
.007,.011,
.007695,.010939,
.008368,.010759,
.009,.010464,
.009571,.010064,
.010064,.009571,
.010464,.009,
.010759,.008368,
.010939,.007695,
.011,.007,
.011,-.007,
.010939,-.007695,
.010759,-.008368,
.010464,-.009,
.010064,-.009571,
.009571,-.010064,
.009,-.010464,
.008368,-.010759,
.007695,-.010939,
.007,-.011,
0.0*
%
%ADD27MACRO27*%
%AMMACRO17*
4,1,40,-.011,-.007,
-.011,.007,
-.010939,.007695,
-.010759,.008368,
-.010464,.009,
-.010064,.009571,
-.009571,.010064,
-.009,.010464,
-.008368,.010759,
-.007695,.010939,
-.007,.011,
.007,.011,
.007695,.010939,
.008368,.010759,
.009,.010464,
.009571,.010064,
.010064,.009571,
.010464,.009,
.010759,.008368,
.010939,.007695,
.011,.007,
.011,-.007,
.010939,-.007695,
.010759,-.008368,
.010464,-.009,
.010064,-.009571,
.009571,-.010064,
.009,-.010464,
.008368,-.010759,
.007695,-.010939,
.007,-.011,
-.007,-.011,
-.007695,-.010939,
-.008368,-.010759,
-.009,-.010464,
-.009571,-.010064,
-.010064,-.009571,
-.010464,-.009,
-.010759,-.008368,
-.010939,-.007695,
-.011,-.007,
0.0*
%
%ADD17MACRO17*%
%AMMACRO40*
4,1,40,-.012,-.008,
-.012,.008,
-.011939,.008695,
-.011759,.009368,
-.011464,.01,
-.011064,.010571,
-.010571,.011064,
-.01,.011464,
-.009368,.011759,
-.008695,.011939,
-.008,.012,
.008,.012,
.008695,.011939,
.009368,.011759,
.01,.011464,
.010571,.011064,
.011064,.010571,
.011464,.01,
.011759,.009368,
.011939,.008695,
.012,.008,
.012,-.008,
.011939,-.008695,
.011759,-.009368,
.011464,-.01,
.011064,-.010571,
.010571,-.011064,
.01,-.011464,
.009368,-.011759,
.008695,-.011939,
.008,-.012,
-.008,-.012,
-.008695,-.011939,
-.009368,-.011759,
-.01,-.011464,
-.010571,-.011064,
-.011064,-.010571,
-.011464,-.01,
-.011759,-.009368,
-.011939,-.008695,
-.012,-.008,
0.0*
%
%ADD40MACRO40*%
%AMMACRO26*
4,1,40,-.008,.012,
.008,.012,
.008695,.011939,
.009368,.011759,
.01,.011464,
.010571,.011064,
.011064,.010571,
.011464,.01,
.011759,.009368,
.011939,.008695,
.012,.008,
.012,-.008,
.011939,-.008695,
.011759,-.009368,
.011464,-.01,
.011064,-.010571,
.010571,-.011064,
.01,-.011464,
.009368,-.011759,
.008695,-.011939,
.008,-.012,
-.008,-.012,
-.008695,-.011939,
-.009368,-.011759,
-.01,-.011464,
-.010571,-.011064,
-.011064,-.010571,
-.011464,-.01,
-.011759,-.009368,
-.011939,-.008695,
-.012,-.008,
-.012,.008,
-.011939,.008695,
-.011759,.009368,
-.011464,.01,
-.011064,.010571,
-.010571,.011064,
-.01,.011464,
-.009368,.011759,
-.008695,.011939,
-.008,.012,
0.0*
%
%ADD26MACRO26*%
%AMMACRO36*
4,1,40,-.013,.017,
.013,.017,
.013695,.016939,
.014368,.016759,
.015,.016464,
.015571,.016064,
.016064,.015571,
.016464,.015,
.016759,.014368,
.016939,.013695,
.017,.013,
.017,-.013,
.016939,-.013695,
.016759,-.014368,
.016464,-.015,
.016064,-.015571,
.015571,-.016064,
.015,-.016464,
.014368,-.016759,
.013695,-.016939,
.013,-.017,
-.013,-.017,
-.013695,-.016939,
-.014368,-.016759,
-.015,-.016464,
-.015571,-.016064,
-.016064,-.015571,
-.016464,-.015,
-.016759,-.014368,
-.016939,-.013695,
-.017,-.013,
-.017,.013,
-.016939,.013695,
-.016759,.014368,
-.016464,.015,
-.016064,.015571,
-.015571,.016064,
-.015,.016464,
-.014368,.016759,
-.013695,.016939,
-.013,.017,
0.0*
%
%ADD36MACRO36*%
%AMMACRO42*
4,1,40,.017,.013,
.017,-.013,
.016939,-.013695,
.016759,-.014368,
.016464,-.015,
.016064,-.015571,
.015571,-.016064,
.015,-.016464,
.014368,-.016759,
.013695,-.016939,
.013,-.017,
-.013,-.017,
-.013695,-.016939,
-.014368,-.016759,
-.015,-.016464,
-.015571,-.016064,
-.016064,-.015571,
-.016464,-.015,
-.016759,-.014368,
-.016939,-.013695,
-.017,-.013,
-.017,.013,
-.016939,.013695,
-.016759,.014368,
-.016464,.015,
-.016064,.015571,
-.015571,.016064,
-.015,.016464,
-.014368,.016759,
-.013695,.016939,
-.013,.017,
.013,.017,
.013695,.016939,
.014368,.016759,
.015,.016464,
.015571,.016064,
.016064,.015571,
.016464,.015,
.016759,.014368,
.016939,.013695,
.017,.013,
0.0*
%
%ADD42MACRO42*%
%AMMACRO28*
4,1,40,.007,-.011,
-.007,-.011,
-.007695,-.010939,
-.008368,-.010759,
-.009,-.010464,
-.009571,-.010064,
-.010064,-.009571,
-.010464,-.009,
-.010759,-.008368,
-.010939,-.007695,
-.011,-.007,
-.011,.007,
-.010939,.007695,
-.010759,.008368,
-.010464,.009,
-.010064,.009571,
-.009571,.010064,
-.009,.010464,
-.008368,.010759,
-.007695,.010939,
-.007,.011,
.007,.011,
.007695,.010939,
.008368,.010759,
.009,.010464,
.009571,.010064,
.010064,.009571,
.010464,.009,
.010759,.008368,
.010939,.007695,
.011,.007,
.011,-.007,
.010939,-.007695,
.010759,-.008368,
.010464,-.009,
.010064,-.009571,
.009571,-.010064,
.009,-.010464,
.008368,-.010759,
.007695,-.010939,
.007,-.011,
0.0*
%
%ADD28MACRO28*%
%AMMACRO18*
4,1,40,-.011,-.007,
-.011,.007,
-.010939,.007695,
-.010759,.008368,
-.010464,.009,
-.010064,.009571,
-.009571,.010064,
-.009,.010464,
-.008368,.010759,
-.007695,.010939,
-.007,.011,
.007,.011,
.007695,.010939,
.008368,.010759,
.009,.010464,
.009571,.010064,
.010064,.009571,
.010464,.009,
.010759,.008368,
.010939,.007695,
.011,.007,
.011,-.007,
.010939,-.007695,
.010759,-.008368,
.010464,-.009,
.010064,-.009571,
.009571,-.010064,
.009,-.010464,
.008368,-.010759,
.007695,-.010939,
.007,-.011,
-.007,-.011,
-.007695,-.010939,
-.008368,-.010759,
-.009,-.010464,
-.009571,-.010064,
-.010064,-.009571,
-.010464,-.009,
-.010759,-.008368,
-.010939,-.007695,
-.011,-.007,
0.0*
%
%ADD18MACRO18*%
%AMMACRO39*
4,1,40,-.012,-.008,
-.012,.008,
-.011939,.008695,
-.011759,.009368,
-.011464,.01,
-.011064,.010571,
-.010571,.011064,
-.01,.011464,
-.009368,.011759,
-.008695,.011939,
-.008,.012,
.008,.012,
.008695,.011939,
.009368,.011759,
.01,.011464,
.010571,.011064,
.011064,.010571,
.011464,.01,
.011759,.009368,
.011939,.008695,
.012,.008,
.012,-.008,
.011939,-.008695,
.011759,-.009368,
.011464,-.01,
.011064,-.010571,
.010571,-.011064,
.01,-.011464,
.009368,-.011759,
.008695,-.011939,
.008,-.012,
-.008,-.012,
-.008695,-.011939,
-.009368,-.011759,
-.01,-.011464,
-.010571,-.011064,
-.011064,-.010571,
-.011464,-.01,
-.011759,-.009368,
-.011939,-.008695,
-.012,-.008,
0.0*
%
%ADD39MACRO39*%
%AMMACRO25*
4,1,40,-.008,.012,
.008,.012,
.008695,.011939,
.009368,.011759,
.01,.011464,
.010571,.011064,
.011064,.010571,
.011464,.01,
.011759,.009368,
.011939,.008695,
.012,.008,
.012,-.008,
.011939,-.008695,
.011759,-.009368,
.011464,-.01,
.011064,-.010571,
.010571,-.011064,
.01,-.011464,
.009368,-.011759,
.008695,-.011939,
.008,-.012,
-.008,-.012,
-.008695,-.011939,
-.009368,-.011759,
-.01,-.011464,
-.010571,-.011064,
-.011064,-.010571,
-.011464,-.01,
-.011759,-.009368,
-.011939,-.008695,
-.012,-.008,
-.012,.008,
-.011939,.008695,
-.011759,.009368,
-.011464,.01,
-.011064,.010571,
-.010571,.011064,
-.01,.011464,
-.009368,.011759,
-.008695,.011939,
-.008,.012,
0.0*
%
%ADD25MACRO25*%
%AMMACRO37*
4,1,40,-.013,.017,
.013,.017,
.013695,.016939,
.014368,.016759,
.015,.016464,
.015571,.016064,
.016064,.015571,
.016464,.015,
.016759,.014368,
.016939,.013695,
.017,.013,
.017,-.013,
.016939,-.013695,
.016759,-.014368,
.016464,-.015,
.016064,-.015571,
.015571,-.016064,
.015,-.016464,
.014368,-.016759,
.013695,-.016939,
.013,-.017,
-.013,-.017,
-.013695,-.016939,
-.014368,-.016759,
-.015,-.016464,
-.015571,-.016064,
-.016064,-.015571,
-.016464,-.015,
-.016759,-.014368,
-.016939,-.013695,
-.017,-.013,
-.017,.013,
-.016939,.013695,
-.016759,.014368,
-.016464,.015,
-.016064,.015571,
-.015571,.016064,
-.015,.016464,
-.014368,.016759,
-.013695,.016939,
-.013,.017,
0.0*
%
%ADD37MACRO37*%
%AMMACRO43*
4,1,40,.017,.013,
.017,-.013,
.016939,-.013695,
.016759,-.014368,
.016464,-.015,
.016064,-.015571,
.015571,-.016064,
.015,-.016464,
.014368,-.016759,
.013695,-.016939,
.013,-.017,
-.013,-.017,
-.013695,-.016939,
-.014368,-.016759,
-.015,-.016464,
-.015571,-.016064,
-.016064,-.015571,
-.016464,-.015,
-.016759,-.014368,
-.016939,-.013695,
-.017,-.013,
-.017,.013,
-.016939,.013695,
-.016759,.014368,
-.016464,.015,
-.016064,.015571,
-.015571,.016064,
-.015,.016464,
-.014368,.016759,
-.013695,.016939,
-.013,.017,
.013,.017,
.013695,.016939,
.014368,.016759,
.015,.016464,
.015571,.016064,
.016064,.015571,
.016464,.015,
.016759,.014368,
.016939,.013695,
.017,.013,
0.0*
%
%ADD43MACRO43*%
%ADD47R,.042X.014*%
%ADD46R,.014X.042*%
%ADD38R,.045X.03*%
%ADD22R,.03X.045*%
%ADD49R,.038X.012*%
%ADD48R,.012X.038*%
%ADD30R,.016X.06*%
%ADD10C,.14*%
%ADD21R,.065X.05*%
%ADD44R,.045X.055*%
%ADD41R,.014X.076*%
%ADD29R,.076X.014*%
%ADD31R,.055X.045*%
%ADD45R,.128X.128*%
%AMMACRO12*
4,1,40,-.02,-.006,
-.019878,-.007389,
-.019518,-.008736,
-.018928,-.01,
-.018128,-.011142,
-.017142,-.012128,
-.016,-.012928,
-.014736,-.013518,
-.013389,-.013878,
-.012,-.014,
.012,-.014,
.013389,-.013878,
.014736,-.013518,
.016,-.012928,
.017142,-.012128,
.018128,-.011142,
.018928,-.01,
.019518,-.008736,
.019878,-.007389,
.02,-.006,
.02,.006,
.019878,.007389,
.019518,.008736,
.018928,.01,
.018128,.011142,
.017142,.012128,
.016,.012928,
.014736,.013518,
.013389,.013878,
.012,.014,
-.012,.014,
-.013389,.013878,
-.014736,.013518,
-.016,.012928,
-.017142,.012128,
-.018128,.011142,
-.018928,.01,
-.019518,.008736,
-.019878,.007389,
-.02,.006,
-.02,-.006,
0.0*
%
%ADD12MACRO12*%
%AMMACRO33*
4,1,40,.012,.008,
.012,-.008,
.011939,-.008695,
.011759,-.009368,
.011464,-.01,
.011064,-.010571,
.010571,-.011064,
.01,-.011464,
.009368,-.011759,
.008695,-.011939,
.008,-.012,
-.008,-.012,
-.008695,-.011939,
-.009368,-.011759,
-.01,-.011464,
-.010571,-.011064,
-.011064,-.010571,
-.011464,-.01,
-.011759,-.009368,
-.011939,-.008695,
-.012,-.008,
-.012,.008,
-.011939,.008695,
-.011759,.009368,
-.011464,.01,
-.011064,.010571,
-.010571,.011064,
-.01,.011464,
-.009368,.011759,
-.008695,.011939,
-.008,.012,
.008,.012,
.008695,.011939,
.009368,.011759,
.01,.011464,
.010571,.011064,
.011064,.010571,
.011464,.01,
.011759,.009368,
.011939,.008695,
.012,.008,
0.0*
%
%ADD33MACRO33*%
%AMMACRO20*
4,1,40,-.007,.011,
.007,.011,
.007695,.010939,
.008368,.010759,
.009,.010464,
.009571,.010064,
.010064,.009571,
.010464,.009,
.010759,.008368,
.010939,.007695,
.011,.007,
.011,-.007,
.010939,-.007695,
.010759,-.008368,
.010464,-.009,
.010064,-.009571,
.009571,-.010064,
.009,-.010464,
.008368,-.010759,
.007695,-.010939,
.007,-.011,
-.007,-.011,
-.007695,-.010939,
-.008368,-.010759,
-.009,-.010464,
-.009571,-.010064,
-.010064,-.009571,
-.010464,-.009,
-.010759,-.008368,
-.010939,-.007695,
-.011,-.007,
-.011,.007,
-.010939,.007695,
-.010759,.008368,
-.010464,.009,
-.010064,.009571,
-.009571,.010064,
-.009,.010464,
-.008368,.010759,
-.007695,.010939,
-.007,.011,
0.0*
%
%ADD20MACRO20*%
%AMMACRO14*
4,1,40,.008,-.012,
-.008,-.012,
-.008695,-.011939,
-.009368,-.011759,
-.01,-.011464,
-.010571,-.011064,
-.011064,-.010571,
-.011464,-.01,
-.011759,-.009368,
-.011939,-.008695,
-.012,-.008,
-.012,.008,
-.011939,.008695,
-.011759,.009368,
-.011464,.01,
-.011064,.010571,
-.010571,.011064,
-.01,.011464,
-.009368,.011759,
-.008695,.011939,
-.008,.012,
.008,.012,
.008695,.011939,
.009368,.011759,
.01,.011464,
.010571,.011064,
.011064,.010571,
.011464,.01,
.011759,.009368,
.011939,.008695,
.012,.008,
.012,-.008,
.011939,-.008695,
.011759,-.009368,
.011464,-.01,
.011064,-.010571,
.010571,-.011064,
.01,-.011464,
.009368,-.011759,
.008695,-.011939,
.008,-.012,
0.0*
%
%ADD14MACRO14*%
%AMMACRO15*
4,1,40,.011,.007,
.011,-.007,
.010939,-.007695,
.010759,-.008368,
.010464,-.009,
.010064,-.009571,
.009571,-.010064,
.009,-.010464,
.008368,-.010759,
.007695,-.010939,
.007,-.011,
-.007,-.011,
-.007695,-.010939,
-.008368,-.010759,
-.009,-.010464,
-.009571,-.010064,
-.010064,-.009571,
-.010464,-.009,
-.010759,-.008368,
-.010939,-.007695,
-.011,-.007,
-.011,.007,
-.010939,.007695,
-.010759,.008368,
-.010464,.009,
-.010064,.009571,
-.009571,.010064,
-.009,.010464,
-.008368,.010759,
-.007695,.010939,
-.007,.011,
.007,.011,
.007695,.010939,
.008368,.010759,
.009,.010464,
.009571,.010064,
.010064,.009571,
.010464,.009,
.010759,.008368,
.010939,.007695,
.011,.007,
0.0*
%
%ADD15MACRO15*%
%AMMACRO34*
4,1,40,-.017,-.013,
-.017,.013,
-.016939,.013695,
-.016759,.014368,
-.016464,.015,
-.016064,.015571,
-.015571,.016064,
-.015,.016464,
-.014368,.016759,
-.013695,.016939,
-.013,.017,
.013,.017,
.013695,.016939,
.014368,.016759,
.015,.016464,
.015571,.016064,
.016064,.015571,
.016464,.015,
.016759,.014368,
.016939,.013695,
.017,.013,
.017,-.013,
.016939,-.013695,
.016759,-.014368,
.016464,-.015,
.016064,-.015571,
.015571,-.016064,
.015,-.016464,
.014368,-.016759,
.013695,-.016939,
.013,-.017,
-.013,-.017,
-.013695,-.016939,
-.014368,-.016759,
-.015,-.016464,
-.015571,-.016064,
-.016064,-.015571,
-.016464,-.015,
-.016759,-.014368,
-.016939,-.013695,
-.017,-.013,
0.0*
%
%ADD34MACRO34*%
%AMMACRO23*
4,1,40,.013,-.017,
-.013,-.017,
-.013695,-.016939,
-.014368,-.016759,
-.015,-.016464,
-.015571,-.016064,
-.016064,-.015571,
-.016464,-.015,
-.016759,-.014368,
-.016939,-.013695,
-.017,-.013,
-.017,.013,
-.016939,.013695,
-.016759,.014368,
-.016464,.015,
-.016064,.015571,
-.015571,.016064,
-.015,.016464,
-.014368,.016759,
-.013695,.016939,
-.013,.017,
.013,.017,
.013695,.016939,
.014368,.016759,
.015,.016464,
.015571,.016064,
.016064,.015571,
.016464,.015,
.016759,.014368,
.016939,.013695,
.017,.013,
.017,-.013,
.016939,-.013695,
.016759,-.014368,
.016464,-.015,
.016064,-.015571,
.015571,-.016064,
.015,-.016464,
.014368,-.016759,
.013695,-.016939,
.013,-.017,
0.0*
%
%ADD23MACRO23*%
%AMMACRO32*
4,1,40,.012,.008,
.012,-.008,
.011939,-.008695,
.011759,-.009368,
.011464,-.01,
.011064,-.010571,
.010571,-.011064,
.01,-.011464,
.009368,-.011759,
.008695,-.011939,
.008,-.012,
-.008,-.012,
-.008695,-.011939,
-.009368,-.011759,
-.01,-.011464,
-.010571,-.011064,
-.011064,-.010571,
-.011464,-.01,
-.011759,-.009368,
-.011939,-.008695,
-.012,-.008,
-.012,.008,
-.011939,.008695,
-.011759,.009368,
-.011464,.01,
-.011064,.010571,
-.010571,.011064,
-.01,.011464,
-.009368,.011759,
-.008695,.011939,
-.008,.012,
.008,.012,
.008695,.011939,
.009368,.011759,
.01,.011464,
.010571,.011064,
.011064,.010571,
.011464,.01,
.011759,.009368,
.011939,.008695,
.012,.008,
0.0*
%
%ADD32MACRO32*%
%AMMACRO19*
4,1,40,-.007,.011,
.007,.011,
.007695,.010939,
.008368,.010759,
.009,.010464,
.009571,.010064,
.010064,.009571,
.010464,.009,
.010759,.008368,
.010939,.007695,
.011,.007,
.011,-.007,
.010939,-.007695,
.010759,-.008368,
.010464,-.009,
.010064,-.009571,
.009571,-.010064,
.009,-.010464,
.008368,-.010759,
.007695,-.010939,
.007,-.011,
-.007,-.011,
-.007695,-.010939,
-.008368,-.010759,
-.009,-.010464,
-.009571,-.010064,
-.010064,-.009571,
-.010464,-.009,
-.010759,-.008368,
-.010939,-.007695,
-.011,-.007,
-.011,.007,
-.010939,.007695,
-.010759,.008368,
-.010464,.009,
-.010064,.009571,
-.009571,.010064,
-.009,.010464,
-.008368,.010759,
-.007695,.010939,
-.007,.011,
0.0*
%
%ADD19MACRO19*%
%AMMACRO13*
4,1,40,.008,-.012,
-.008,-.012,
-.008695,-.011939,
-.009368,-.011759,
-.01,-.011464,
-.010571,-.011064,
-.011064,-.010571,
-.011464,-.01,
-.011759,-.009368,
-.011939,-.008695,
-.012,-.008,
-.012,.008,
-.011939,.008695,
-.011759,.009368,
-.011464,.01,
-.011064,.010571,
-.010571,.011064,
-.01,.011464,
-.009368,.011759,
-.008695,.011939,
-.008,.012,
.008,.012,
.008695,.011939,
.009368,.011759,
.01,.011464,
.010571,.011064,
.011064,.010571,
.011464,.01,
.011759,.009368,
.011939,.008695,
.012,.008,
.012,-.008,
.011939,-.008695,
.011759,-.009368,
.011464,-.01,
.011064,-.010571,
.010571,-.011064,
.01,-.011464,
.009368,-.011759,
.008695,-.011939,
.008,-.012,
0.0*
%
%ADD13MACRO13*%
%ADD51C,.02*%
%ADD52C,.006*%
G75*
%LPD*%
G75*
G54D10*
X-1011811Y-15748D03*
Y940945D03*
X775591Y-15748D03*
Y940944D03*
G54D20*
X65768Y198735D03*
X76106Y185541D03*
X65759Y202789D03*
X63600Y251200D03*
X65747Y206909D03*
X60883Y381140D03*
X74163Y386683D03*
X58907Y450659D03*
X58950Y455007D03*
X46873Y528179D03*
X79700Y144900D03*
X86500Y225900D03*
X87950Y409763D03*
X92863Y401383D03*
X91964Y405439D03*
X179964Y294017D03*
X420038Y471346D03*
X420032Y475470D03*
X696800Y511400D03*
X697256Y825792D03*
X715645Y485000D03*
Y480900D03*
X716300Y529600D03*
Y525500D03*
X714226Y560695D03*
X741382Y850566D03*
X741362Y846447D03*
X741500Y859500D03*
G54D11*
X-944882Y-17185D03*
Y942382D03*
X57900Y226200D03*
X182900Y308800D03*
X708683Y-17218D03*
G54D12*
X76107Y131131D03*
Y138611D03*
X83977Y134871D03*
G54D21*
X50244Y180974D03*
Y191974D03*
X44879Y511272D03*
Y522272D03*
G54D30*
X32984Y299567D03*
X30424D03*
X27864D03*
X25304D03*
Y283267D03*
X27864D03*
X30424D03*
X32984D03*
X687385Y518741D03*
X689945D03*
X692505D03*
X695065D03*
Y535041D03*
X692505D03*
X689945D03*
X687385D03*
X712102Y553333D03*
Y537033D03*
X654710Y540455D03*
X657270D03*
X659830D03*
X662390D03*
Y556755D03*
X659830D03*
X657270D03*
X654710D03*
X719782Y553333D03*
X717222D03*
X714662D03*
Y537033D03*
X717222D03*
X719782D03*
G54D13*
X55700Y87600D03*
X59274Y87603D03*
X35230Y306738D03*
X134663Y456583D03*
X681300Y510400D03*
X648500Y536800D03*
X677800Y510400D03*
X725784Y554587D03*
G54D31*
X75876Y307064D03*
Y314664D03*
X50799Y499966D03*
Y492366D03*
X400934Y446386D03*
Y453986D03*
X393110Y446429D03*
Y454029D03*
G54D22*
X65830Y181464D03*
X58080D03*
X61955Y188964D03*
X56759Y199321D03*
X49009D03*
X52884Y206821D03*
G54D40*
X65600Y609872D03*
Y605972D03*
X65700Y600272D03*
Y596372D03*
Y576887D03*
Y572987D03*
X65800Y567387D03*
Y563487D03*
X66251Y694403D03*
Y690503D03*
Y684703D03*
Y680803D03*
X65200Y728513D03*
Y724613D03*
X65300Y718613D03*
Y714713D03*
X134700Y228600D03*
X94363Y228783D03*
X94419Y305456D03*
X124863Y305503D03*
X135563Y305603D03*
X110405Y413570D03*
X118463Y421283D03*
X124563Y441583D03*
X125363Y449983D03*
X116963Y441583D03*
X113063Y434383D03*
X139763Y441583D03*
X133263Y449183D03*
X122863Y433683D03*
X130583Y434871D03*
Y431371D03*
X133263Y452683D03*
X175296Y269694D03*
X171869Y432425D03*
X160663Y440683D03*
X154240Y837095D03*
X154351Y832781D03*
Y828981D03*
X155836Y817740D03*
Y814140D03*
X155088Y853750D03*
X155161Y850210D03*
X154040Y840895D03*
X711530Y464221D03*
X711609Y453723D03*
X657300Y533400D03*
G54D32*
X60983Y392640D03*
Y389240D03*
X63585Y496598D03*
X120763Y228683D03*
X110063Y228783D03*
X109736Y306270D03*
X91863Y382983D03*
X106257Y409989D03*
X91752Y379460D03*
X95400Y455100D03*
X110863Y430483D03*
X115063Y448583D03*
X118880Y465509D03*
X132163Y441583D03*
X118813Y461961D03*
X118794Y458462D03*
X150563Y228783D03*
X150763Y305503D03*
X172478Y473409D03*
X171943Y469870D03*
X149899Y461877D03*
X679465Y467377D03*
Y463877D03*
X681909Y453623D03*
X679684Y546217D03*
X714291Y564572D03*
G54D23*
X47940Y212898D03*
G54D14*
X55700Y91200D03*
X59274Y91203D03*
X35230Y310338D03*
X134663Y460183D03*
X681300Y514000D03*
X648500Y540400D03*
X677800Y514000D03*
X725784Y558187D03*
G54D41*
X82858Y236883D03*
X85418D03*
X87973D03*
X90533D03*
X93093D03*
X95653D03*
X98213D03*
X100768D03*
X103328D03*
X105888D03*
X108448D03*
X111008D03*
X113563D03*
X116123D03*
X118683D03*
X146833D03*
X144273D03*
X141713D03*
X139158D03*
X136598D03*
X134038D03*
X131478D03*
X128918D03*
X126363D03*
X123803D03*
X121243D03*
X146833Y297283D03*
X144273D03*
X141713D03*
X139158D03*
X136598D03*
X134038D03*
X131478D03*
X128918D03*
X126363D03*
X123803D03*
X121243D03*
X82858D03*
X85418D03*
X87973D03*
X90533D03*
X93093D03*
X95653D03*
X98213D03*
X100768D03*
X103328D03*
X105888D03*
X108448D03*
X111008D03*
X113563D03*
X116123D03*
X118683D03*
X157068Y236883D03*
X154508D03*
X151953D03*
X149393D03*
X157068Y297283D03*
X154508D03*
X151953D03*
X149393D03*
G54D50*
X694858Y466020D03*
G54D51*
G01X-771361Y-182763D02*
Y-262763D01*
G01Y-218263D02*
X373639D01*
G01X-771361Y-262763D02*
X373639D01*
G01X-775361Y-166763D02*
G02I-12000J0D01*
G01X-780511D02*
G02I-6850J0D01*
G01X-787361Y-182763D02*
Y-150763D01*
G01X-771361Y-166763D02*
X-803361D01*
G01X-771361Y-182763D02*
X373639D01*
G01X-413861D02*
Y-262763D01*
G01X-276361Y-182763D02*
Y-262763D01*
G01X-161361Y-182763D02*
Y-262763D01*
G01X6139Y-182763D02*
Y-262763D01*
G01X176139Y-182763D02*
Y-262763D01*
G01X373639Y-182763D02*
Y-262763D01*
G01X401639Y-166763D02*
G02I-12000J0D01*
G01X396489D02*
G02I-6850J0D01*
G01X389639Y-182763D02*
Y-150763D01*
G01X405639Y-166763D02*
X373639D01*
G54D15*
X74800Y87800D03*
X43851Y178828D03*
X43794Y193758D03*
X22900Y310200D03*
X39236Y280487D03*
X27000Y310100D03*
X31100D03*
X63942Y534279D03*
X67065Y515737D03*
X98138Y402278D03*
X89163Y386883D03*
X94076Y411254D03*
X118163Y470983D03*
X149799Y448926D03*
X428616Y433629D03*
X684869Y434811D03*
X680738Y434833D03*
X693509Y434901D03*
X689111Y434812D03*
X705600Y551200D03*
X663300Y526200D03*
X648200Y552100D03*
X705927Y528727D03*
X668699Y552630D03*
X726040Y547196D03*
G54D33*
X57383Y392640D03*
Y389240D03*
X59985Y496598D03*
X146963Y228783D03*
X117163Y228683D03*
X106463Y228783D03*
X106136Y306270D03*
X147163Y305503D03*
X88263Y382983D03*
X102657Y409989D03*
X88152Y379460D03*
X91800Y455100D03*
X107263Y430483D03*
X111463Y448583D03*
X115280Y465509D03*
X128563Y441583D03*
X146299Y461877D03*
X115213Y461961D03*
X115194Y458462D03*
X168878Y473409D03*
X168343Y469870D03*
X675865Y467377D03*
Y463877D03*
X678309Y453623D03*
X676084Y546217D03*
X710691Y564572D03*
G54D42*
X102363Y449283D03*
X125579Y421573D03*
X701500Y518600D03*
X680800D03*
G54D24*
X53540Y212898D03*
G54D52*
G01X-1003937Y-3937D02*
G03X-1000000Y-7874I3937J0D01*
G01X-1031496Y-31496D02*
G03X-1027559Y-35433I3937J0D01*
G01X-986221Y-7874D02*
G03Y0I0J3937D01*
G01Y-7874D02*
X-1000000D01*
G01X-1027559Y-35433D02*
X791338D01*
G01X-1031496Y95866D02*
Y-31496D01*
G01X-996063Y3937D02*
G03X-992126Y0I3937J0D01*
G01X-996063Y39370D02*
G03X-1003937I-3937J0D01*
G01X-996063Y3937D02*
G03X-992126Y0I3937J0D01*
G01D02*
X-318898D01*
G01D02*
X-992126D01*
G01X-955512D02*
X-986221D01*
G01X-996063Y3937D02*
Y103740D01*
G01Y39370D02*
Y70079D01*
G01X-1003937Y-3937D02*
Y39370D01*
G01X-1027559Y99803D02*
G03X-1031496Y95866I0J-3937D01*
G01X-1003937D02*
G03X-1007874Y99803I-3937J0D01*
G01X-996063Y103740D02*
G03X-1000000Y107677I-3937J0D01*
G01X-1003937Y70079D02*
G03X-996063I3937J0D01*
G01X-1029528Y107677D02*
X-1000000D01*
G01X-1007874Y99803D02*
X-1027559D01*
G01X-1003937Y70079D02*
Y95866D01*
G01X-1031496Y109646D02*
X-1029528Y107677D01*
G01X-1031496Y109646D02*
Y134055D01*
G01X-1002166Y136024D02*
G03Y143504I0J3740D01*
G01X-1000000Y187599D02*
G03X-996063Y191536I0J3937D01*
G01X-1029528Y187599D02*
X-1000000D01*
G01X-1029528Y143504D02*
X-1002166D01*
G01X-1029528Y136024D02*
X-1002166D01*
G01X-1029528D02*
X-1031496Y134055D01*
G01X-1029528Y187599D02*
X-1031496Y185630D01*
G01Y145473D02*
X-1029528Y143504D01*
G01X-996063Y261221D02*
Y191536D01*
G01X-1031496Y145473D02*
Y185630D01*
G01X-996063Y261221D02*
G03X-1000000Y265158I-3937J0D01*
G01X-1029528D02*
X-1000000D01*
G01X-1031496Y267126D02*
X-1029528Y265158D01*
G01X-1031496Y267126D02*
Y543504D01*
G01X-1002166Y545473D02*
G03Y552953I0J3740D01*
G01X-1029528D02*
X-1002166D01*
G01X-1029528Y545473D02*
X-1002166D01*
G01X-1031496Y554922D02*
X-1029528Y552953D01*
G01Y545473D02*
X-1031496Y543504D01*
G01Y554922D02*
Y595079D01*
G01X-1007874Y604922D02*
G03X-1003937Y608859I0J3937D01*
G01X-1031496D02*
G03X-1027559Y604922I3937J0D01*
G01X-1000000Y597048D02*
G03X-996063Y600985I0J3937D01*
G01X-1027559Y604922D02*
X-1007874D01*
G01X-1029528Y597048D02*
X-1000000D01*
G01X-1029528D02*
X-1031496Y595079D01*
G01X-996063Y921260D02*
Y600985D01*
G01X-1003937Y608859D02*
Y708662D01*
G01X-1031496Y956693D02*
Y608859D01*
G01X-1003937Y739370D02*
G03X-996063I3937J0D01*
G01Y708662D02*
G03X-1003937I-3937J0D01*
G01X-996063D02*
Y739370D01*
G01X-1003937D02*
Y929134D01*
G01X-992126Y925197D02*
G03X-996063Y921260I0J-3937D01*
G01X-1000000Y933071D02*
G03X-1003937Y929134I0J-3937D01*
G01X-986221Y925197D02*
G03Y933071I0J3937D01*
G01X-1027559Y960630D02*
G03X-1031496Y956693I0J-3937D01*
G01X-992126Y925197D02*
G03X-996063Y921260I0J-3937D01*
G01X791338Y960630D02*
X-1027559D01*
G01X-1000000Y933071D02*
X-986221D01*
G01X-992126Y925197D02*
X-240158D01*
G01X-986221D02*
X-955512D01*
G01X-992126D02*
X-240158D01*
G01X-955512Y0D02*
G03Y-7874I0J-3937D01*
G01X-769685D02*
X-955512D01*
G01Y933071D02*
G03Y925197I0J-3937D01*
G01Y933071D02*
X-750000D01*
G01X-769685Y-7874D02*
G03Y0I0J3937D01*
G01X-738977D02*
X-769685D01*
G01X-755164Y-252763D02*
Y-235263D01*
G01X-746868D02*
X-755164Y-246055D01*
G01X-745558Y-252763D02*
X-751453Y-241097D01*
G01X-737883Y-252763D02*
Y-235263D01*
X-727839Y-252763D01*
Y-235263D01*
G01X-715361Y-252763D02*
X-717108Y-252471D01*
X-718636Y-251305D01*
X-719946Y-249555D01*
X-720820Y-247513D01*
X-721256Y-245180D01*
Y-242846D01*
X-720820Y-240513D01*
X-719946Y-238471D01*
X-718636Y-236722D01*
X-717108Y-235555D01*
X-715361Y-235263D01*
X-713615Y-235555D01*
X-712086Y-236722D01*
X-710776Y-238471D01*
X-709902Y-240513D01*
X-709466Y-242846D01*
Y-245180D01*
X-709902Y-247513D01*
X-710776Y-249555D01*
X-712086Y-251305D01*
X-713615Y-252471D01*
X-715361Y-252763D01*
G01X-702446D02*
X-693276Y-235263D01*
G01X-702446D02*
X-693276Y-252763D01*
G01X-658494D02*
X-667228D01*
Y-235263D01*
X-658494D01*
G01X-661988Y-243721D02*
X-667228D01*
G01X-649946Y-252763D02*
X-640776Y-235263D01*
G01X-649946D02*
X-640776Y-252763D01*
G01X-632228D02*
Y-235263D01*
X-626988D01*
X-625241Y-236138D01*
X-623931Y-238180D01*
X-623494Y-240513D01*
X-623931Y-242846D01*
X-625023Y-244596D01*
X-626988Y-245472D01*
X-632228D01*
G01X-615820Y-252763D02*
X-610361Y-235263D01*
X-604902Y-252763D01*
G01X-606868Y-246638D02*
X-613855D01*
G01X-597883Y-252763D02*
Y-235263D01*
X-587839Y-252763D01*
Y-235263D01*
G01X-580164Y-252763D02*
Y-235263D01*
X-575798D01*
X-574051Y-236138D01*
X-572741Y-237305D01*
X-571649Y-239054D01*
X-570776Y-241097D01*
X-570558Y-244013D01*
X-570776Y-246930D01*
X-571649Y-248972D01*
X-572741Y-250722D01*
X-574051Y-251888D01*
X-575798Y-252763D01*
X-580164D01*
G01X-553494D02*
X-562228D01*
Y-235263D01*
X-553494D01*
G01X-556988Y-243721D02*
X-562228D01*
G01X-544728Y-252763D02*
Y-235263D01*
X-539269D01*
X-537523Y-236138D01*
X-536431Y-237305D01*
X-535994Y-239638D01*
X-536431Y-241972D01*
X-537741Y-243430D01*
X-539269Y-244305D01*
X-544728D01*
G01X-539269D02*
X-535994Y-252763D01*
G01X-503615Y-243430D02*
X-502741Y-242555D01*
X-502086Y-241097D01*
X-501649Y-239054D01*
X-502086Y-237305D01*
X-502959Y-236138D01*
X-504488Y-235263D01*
X-510383D01*
Y-252763D01*
X-503178D01*
X-501649Y-251597D01*
X-500776Y-249846D01*
X-500339Y-247805D01*
X-500776Y-245763D01*
X-502086Y-244013D01*
X-503615Y-243430D01*
X-510383D01*
G01X-487861Y-252763D02*
X-489608Y-252471D01*
X-491136Y-251305D01*
X-492446Y-249555D01*
X-493320Y-247513D01*
X-493756Y-245180D01*
Y-242846D01*
X-493320Y-240513D01*
X-492446Y-238471D01*
X-491136Y-236722D01*
X-489608Y-235555D01*
X-487861Y-235263D01*
X-486115Y-235555D01*
X-484586Y-236722D01*
X-483276Y-238471D01*
X-482402Y-240513D01*
X-481966Y-242846D01*
Y-245180D01*
X-482402Y-247513D01*
X-483276Y-249555D01*
X-484586Y-251305D01*
X-486115Y-252471D01*
X-487861Y-252763D01*
G01X-475820D02*
X-470361Y-235263D01*
X-464902Y-252763D01*
G01X-466868Y-246638D02*
X-473855D01*
G01X-457228Y-252763D02*
Y-235263D01*
X-451769D01*
X-450023Y-236138D01*
X-448931Y-237305D01*
X-448494Y-239638D01*
X-448931Y-241972D01*
X-450241Y-243430D01*
X-451769Y-244305D01*
X-457228D01*
G01X-451769D02*
X-448494Y-252763D01*
G01X-440164D02*
Y-235263D01*
X-435798D01*
X-434051Y-236138D01*
X-432741Y-237305D01*
X-431649Y-239054D01*
X-430776Y-241097D01*
X-430558Y-244013D01*
X-430776Y-246930D01*
X-431649Y-248972D01*
X-432741Y-250722D01*
X-434051Y-251888D01*
X-435798Y-252763D01*
X-440164D01*
G01X-738977Y0D02*
G03Y-7874I0J-3937D01*
G01X-522835D02*
X-738977D01*
G01X-719292Y933071D02*
G03Y925197I0J-3937D01*
G01X-750000D02*
G03Y933071I0J3937D01*
G01X-719292D02*
X-512992D01*
G01X-750000Y925197D02*
X-719292D01*
G01X-633538Y-207763D02*
Y-190263D01*
X-627861Y-204846D01*
X-622184Y-190263D01*
Y-207763D01*
G01X-610361D02*
X-611671Y-207471D01*
X-612981Y-206305D01*
X-613855Y-204263D01*
X-614291Y-201930D01*
X-613855Y-199596D01*
X-612981Y-197555D01*
X-611671Y-196388D01*
X-610361Y-196097D01*
X-609051Y-196388D01*
X-607741Y-197555D01*
X-606868Y-199596D01*
X-606649Y-201930D01*
X-606868Y-204263D01*
X-607741Y-206305D01*
X-609051Y-207471D01*
X-610361Y-207763D01*
G01X-588931Y-190263D02*
Y-207763D01*
G01Y-205139D02*
X-589804Y-206597D01*
X-591115Y-207471D01*
X-592643Y-207763D01*
X-594389Y-207180D01*
X-595699Y-205722D01*
X-596573Y-203972D01*
X-596791Y-201930D01*
X-596573Y-199888D01*
X-595699Y-198138D01*
X-594389Y-196680D01*
X-592643Y-196097D01*
X-591115Y-196388D01*
X-590023Y-196972D01*
X-588931Y-198138D01*
G01X-578636Y-199888D02*
X-571649D01*
X-572304Y-197846D01*
X-573396Y-196680D01*
X-574924Y-196097D01*
X-576453Y-196388D01*
X-577763Y-197263D01*
X-578636Y-199305D01*
X-579073Y-201055D01*
Y-202805D01*
X-578636Y-204555D01*
X-577544Y-206305D01*
X-576234Y-207471D01*
X-574706Y-207763D01*
X-573178Y-207180D01*
X-571649Y-205430D01*
G01X-557861Y-207763D02*
Y-190263D01*
G01X-522835Y-7874D02*
G03Y0I0J3937D01*
G01X-492126D02*
G03Y-7874I0J-3937D01*
G01X-365355D02*
X-492126D01*
G01Y0D02*
X-522835D01*
G01X-482284Y933071D02*
G03Y925197I0J-3937D01*
G01X-512992D02*
G03Y933071I0J3937D01*
G01Y925197D02*
X-482284D01*
G01Y933071D02*
X-316142D01*
G01X-380161Y-252763D02*
Y-235263D01*
X-382781Y-238763D01*
G01Y-252763D02*
X-377541D01*
G01X-366809Y-238180D02*
X-365499Y-236430D01*
X-363971Y-235555D01*
X-362224Y-235263D01*
X-360041Y-235846D01*
X-358513Y-237305D01*
X-358076Y-239054D01*
X-358294Y-240805D01*
X-359168Y-242263D01*
X-363534Y-245180D01*
X-365499Y-247221D01*
X-366809Y-250139D01*
X-367246Y-252763D01*
X-358076D01*
G01X-345161Y-235263D02*
X-346908Y-235846D01*
X-348218Y-237305D01*
X-349091Y-239054D01*
X-349746Y-241388D01*
X-349964Y-244013D01*
X-349746Y-246638D01*
X-349091Y-248972D01*
X-348218Y-250722D01*
X-346908Y-252180D01*
X-345161Y-252763D01*
X-343415Y-252180D01*
X-342104Y-250722D01*
X-341231Y-248972D01*
X-340576Y-246638D01*
X-340358Y-244013D01*
X-340576Y-241388D01*
X-341231Y-239054D01*
X-342104Y-237305D01*
X-343415Y-235846D01*
X-345161Y-235263D01*
G01X-327661D02*
X-329408Y-235846D01*
X-330718Y-237305D01*
X-331591Y-239054D01*
X-332246Y-241388D01*
X-332464Y-244013D01*
X-332246Y-246638D01*
X-331591Y-248972D01*
X-330718Y-250722D01*
X-329408Y-252180D01*
X-327661Y-252763D01*
X-325915Y-252180D01*
X-324604Y-250722D01*
X-323731Y-248972D01*
X-323076Y-246638D01*
X-322858Y-244013D01*
X-323076Y-241388D01*
X-323731Y-239054D01*
X-324604Y-237305D01*
X-325915Y-235846D01*
X-327661Y-235263D01*
G01X-307541Y-252763D02*
Y-235263D01*
X-315620Y-247805D01*
X-304702D01*
G01X-393278Y-207763D02*
Y-190263D01*
X-388038D01*
X-386291Y-191138D01*
X-384981Y-193180D01*
X-384544Y-195513D01*
X-384981Y-197846D01*
X-386073Y-199596D01*
X-388038Y-200472D01*
X-393278D01*
G01X-366608Y-191722D02*
X-367918Y-190846D01*
X-369446Y-190263D01*
X-371193D01*
X-373158Y-191138D01*
X-374686Y-192596D01*
X-375778Y-194347D01*
X-376651Y-197263D01*
X-376870Y-199888D01*
X-376433Y-202513D01*
X-375778Y-204263D01*
X-374468Y-206013D01*
X-372939Y-207180D01*
X-371411Y-207763D01*
X-369883D01*
X-368354Y-207180D01*
X-367044Y-206305D01*
X-365952Y-205139D01*
G01X-352165Y-198430D02*
X-351291Y-197555D01*
X-350636Y-196097D01*
X-350199Y-194054D01*
X-350636Y-192305D01*
X-351509Y-191138D01*
X-353038Y-190263D01*
X-358933D01*
Y-207763D01*
X-351728D01*
X-350199Y-206597D01*
X-349326Y-204846D01*
X-348889Y-202805D01*
X-349326Y-200763D01*
X-350636Y-199013D01*
X-352165Y-198430D01*
X-358933D01*
G01X-342961Y-213596D02*
X-329861D01*
G01X-323933Y-207763D02*
Y-190263D01*
X-313889Y-207763D01*
Y-190263D01*
G01X-301411Y-207763D02*
X-303158Y-207471D01*
X-304686Y-206305D01*
X-305996Y-204555D01*
X-306870Y-202513D01*
X-307306Y-200180D01*
Y-197846D01*
X-306870Y-195513D01*
X-305996Y-193471D01*
X-304686Y-191722D01*
X-303158Y-190555D01*
X-301411Y-190263D01*
X-299665Y-190555D01*
X-298136Y-191722D01*
X-296826Y-193471D01*
X-295952Y-195513D01*
X-295516Y-197846D01*
Y-200180D01*
X-295952Y-202513D01*
X-296826Y-204555D01*
X-298136Y-206305D01*
X-299665Y-207471D01*
X-301411Y-207763D01*
G01X-365355Y-7874D02*
G03Y0I0J3937D01*
G01X-334646D02*
X-365355D01*
G01X-311024Y-7874D02*
G03X-307087Y-3937I0J3937D01*
G01X-334646Y0D02*
G03Y-7874I0J-3937D01*
G01X-311024D02*
X-334646D01*
G01X-318898Y0D02*
G03X-314961Y3937I0J3937D01*
G01X-274410Y31595D02*
G03X-270473Y35532I0J3937D01*
G01X-303150Y31595D02*
G03X-307087Y27658I0J-3937D01*
G01X-318898Y0D02*
G03X-314961Y3937I0J3937D01*
G01X-307087Y27658D02*
Y-3937D01*
G01X-314961Y133859D02*
Y3937D01*
G01Y133859D02*
Y3937D01*
G01X-274410Y31595D02*
X-303150D01*
G01X-311024Y137796D02*
G03X-314961Y133859I0J-3937D01*
G01X-311024Y137796D02*
G03X-314961Y133859I0J-3937D01*
G01X-240158Y137796D02*
X-311024D01*
G01X-240158D02*
X-311024D01*
G01X-285433Y933071D02*
G03Y925197I0J-3937D01*
G01X-316142D02*
G03Y933071I0J3937D01*
G01X-285433D02*
X-224410D01*
G01X-316142Y925197D02*
X-285433D01*
G01X-218861Y-252763D02*
Y-235263D01*
X-221481Y-238763D01*
G01Y-252763D02*
X-216241D01*
G01X-250570Y-190263D02*
X-245111Y-207763D01*
X-239652Y-190263D01*
G01X-223244Y-207763D02*
X-231978D01*
Y-190263D01*
X-223244D01*
G01X-226738Y-198721D02*
X-231978D01*
G01X-214478Y-207763D02*
Y-190263D01*
X-209019D01*
X-207273Y-191138D01*
X-206181Y-192305D01*
X-205744Y-194638D01*
X-206181Y-196972D01*
X-207491Y-198430D01*
X-209019Y-199305D01*
X-214478D01*
G01X-209019D02*
X-205744Y-207763D01*
G01X-192611Y-208346D02*
X-193048Y-208055D01*
Y-207471D01*
X-192611Y-207180D01*
X-192174Y-207471D01*
Y-208055D01*
X-192611Y-208346D01*
G01X-270473Y125985D02*
Y35532D01*
G01X-266536Y129922D02*
G03X-270473Y125985I0J-3937D01*
G01X-260630Y129922D02*
G03Y137796I0J3937D01*
G01X-244882D02*
G03Y129922I0J-3937D01*
G01X-240158D02*
G03X-228347Y141733I0J11811D01*
G01X-260630Y129922D02*
X-266536D01*
G01X-240158D02*
X-244882D01*
G01X-240158Y137796D02*
G03X-236221Y141733I0J3937D01*
G01X-240158Y137796D02*
G03X-236221Y141733I0J3937D01*
G01X-228347Y368701D02*
Y141733D01*
G01X-236221Y413386D02*
Y141733D01*
G01X-244882Y137796D02*
X-260630D01*
G01X-204725Y409449D02*
G03X-208662Y405512I0J-3937D01*
G01X-232284Y417323D02*
G03X-236221Y413386I0J-3937D01*
G01X-232284Y417323D02*
G03X-236221Y413386I0J-3937D01*
G01X-212599Y372638D02*
G03X-208662Y376575I0J3937D01*
G01X-224410Y372638D02*
G03X-228347Y368701I0J-3937D01*
G01X-181103Y409449D02*
X-204725D01*
G01X-212599Y372638D02*
X-224410D01*
G01X-208662Y405512D02*
Y376575D01*
G01X-232284Y417323D02*
X-181103D01*
G01X-232284D02*
X-181103D01*
G01X-236221Y716536D02*
G03X-232284Y712599I3937J0D01*
G01X-224410Y724410D02*
G03X-220473Y720473I3937J0D01*
G01X-236221Y716536D02*
G03X-232284Y712599I3937J0D01*
G01X-220473Y720473D02*
X-96418D01*
G01Y712599D02*
X-232284D01*
G01X-96418D02*
X-232284D01*
G01X-224410Y933071D02*
Y724410D01*
G01X-236221Y921260D02*
Y716536D01*
G01Y921260D02*
G03X-240158Y925197I-3937J0D01*
G01X-236221Y921260D02*
G03X-240158Y925197I-3937J0D01*
G01X-143740Y216536D02*
G03X-139803Y212599I3937J0D01*
G01X-143740Y262205D02*
G03X-151614I-3937J0D01*
G01X-143740Y216536D02*
G03X-139803Y212599I3937J0D01*
G01X-151614Y216536D02*
G03X-139803Y204725I11811J0D01*
G01X-143740Y262205D02*
Y292914D01*
G01Y338583D02*
Y216536D01*
G01Y338583D02*
Y216536D01*
G01X-151614D02*
Y262205D01*
G01X-139803Y212599D02*
X-3937D01*
G01X-139803D02*
X-3937D01*
G01X-15748Y204725D02*
X-139803D01*
G01Y342520D02*
G03X-143740Y338583I0J-3937D01*
G01X-139803Y342520D02*
G03X-143740Y338583I0J-3937D01*
G01X-139803Y350394D02*
G03X-151614Y338583I0J-11811D01*
G01Y292914D02*
G03X-143740I3937J0D01*
G01X-151614D02*
Y338583D01*
G01X-62992Y342520D02*
X-139803D01*
G01X-62992D02*
X-139803D01*
G01X-181103Y409449D02*
G03X-169292Y421260I0J11811D01*
G01X-139803Y350394D02*
X-70866D01*
G01X-177166Y467717D02*
G03X-169292I3937J0D01*
G01X-181103Y417323D02*
G03X-177166Y421260I0J3937D01*
G01X-169292Y437008D02*
G03X-177166I-3937J0D01*
G01X-181103Y417323D02*
G03X-177166Y421260I0J3937D01*
G01X-169292Y437008D02*
Y421260D01*
G01Y570866D02*
Y467717D01*
G01X-177166Y421260D02*
Y578740D01*
G01Y421260D02*
Y578740D01*
G01Y467717D02*
Y437008D01*
G01X-173229Y582677D02*
G03X-177166Y578740I0J-3937D01*
G01X-165355Y574803D02*
G03X-169292Y570866I0J-3937D01*
G01X-173229Y582677D02*
G03X-177166Y578740I0J-3937D01*
G01X-173229Y582677D02*
X-96418D01*
G01X-173229D02*
X-96418D01*
G01Y574803D02*
X-165355D01*
G01X-53157Y-243430D02*
X-54031Y-242555D01*
X-54686Y-241097D01*
X-55123Y-239054D01*
X-54686Y-237305D01*
X-53813Y-236138D01*
X-52284Y-235263D01*
X-46389D01*
Y-252763D01*
X-53594D01*
X-55123Y-251597D01*
X-55996Y-249846D01*
X-56433Y-247805D01*
X-55996Y-245763D01*
X-54686Y-244013D01*
X-53157Y-243430D01*
X-46389D01*
G01X-64326Y-250430D02*
X-66073Y-251888D01*
X-68038Y-252763D01*
X-69784D01*
X-71531Y-251888D01*
X-72841Y-250430D01*
X-73496Y-248388D01*
X-73059Y-246347D01*
X-71968Y-244596D01*
X-70003Y-243430D01*
X-67383Y-242846D01*
X-65854Y-241680D01*
X-65199Y-239638D01*
X-65636Y-237596D01*
X-66728Y-236138D01*
X-68256Y-235263D01*
X-69784D01*
X-71313Y-235846D01*
X-72623Y-237305D01*
G01X-80734Y-252763D02*
Y-235263D01*
X-86411Y-249846D01*
X-92088Y-235263D01*
Y-252763D01*
G01X-99108D02*
Y-235263D01*
X-103474D01*
X-105221Y-236138D01*
X-106531Y-237305D01*
X-107623Y-239054D01*
X-108496Y-241097D01*
X-108714Y-244013D01*
X-108496Y-246930D01*
X-107623Y-248972D01*
X-106531Y-250722D01*
X-105221Y-251888D01*
X-103474Y-252763D01*
X-99108D01*
G01X-125778Y-190263D02*
Y-207763D01*
X-117044D01*
G01X-99981D02*
Y-196097D01*
G01Y-198138D02*
X-100854Y-196972D01*
X-102165Y-196388D01*
X-103693Y-196097D01*
X-105221Y-196680D01*
X-106531Y-197846D01*
X-107405Y-199596D01*
X-107841Y-201930D01*
X-107405Y-204263D01*
X-106531Y-206013D01*
X-105221Y-207180D01*
X-103693Y-207763D01*
X-102165Y-207471D01*
X-100854Y-206597D01*
X-99981Y-205430D01*
G01X-90996Y-213013D02*
X-89686Y-213596D01*
X-87939Y-213013D01*
X-86848Y-211847D01*
X-85974Y-210388D01*
X-84665Y-205722D01*
X-81826Y-196097D01*
G01X-88813D02*
X-84665Y-205722D01*
G01X-72186Y-199888D02*
X-65199D01*
X-65854Y-197846D01*
X-66946Y-196680D01*
X-68474Y-196097D01*
X-70003Y-196388D01*
X-71313Y-197263D01*
X-72186Y-199305D01*
X-72623Y-201055D01*
Y-202805D01*
X-72186Y-204555D01*
X-71094Y-206305D01*
X-69784Y-207471D01*
X-68256Y-207763D01*
X-66728Y-207180D01*
X-65199Y-205430D01*
G01X-54468Y-207763D02*
Y-196097D01*
G01Y-198430D02*
X-53376Y-197263D01*
X-52284Y-196388D01*
X-50756Y-196097D01*
X-49665Y-196388D01*
X-48354Y-197263D01*
G01X-37186Y-205722D02*
X-36094Y-206888D01*
X-34566Y-207763D01*
X-33256D01*
X-31946Y-207180D01*
X-31073Y-206305D01*
X-30636Y-205139D01*
X-30854Y-203388D01*
X-31728Y-202513D01*
X-35658Y-200763D01*
X-36531Y-198721D01*
X-36094Y-197263D01*
X-35221Y-196388D01*
X-33911Y-196097D01*
X-32601Y-196388D01*
X-31291Y-197263D01*
G01X-62992Y342520D02*
G03X-59055Y346457I0J3937D01*
G01X-62992Y342520D02*
G03X-59055Y346457I0J3937D01*
G01X-70866Y350394D02*
G03X-66929Y354331I0J3937D01*
G01D02*
Y457481D01*
G01Y488189D02*
G03X-59055I3937J0D01*
G01Y457481D02*
G03X-66929I-3937J0D01*
G01X-55118Y515748D02*
G03X-66929Y503937I0J-11811D01*
G01Y488189D02*
Y503937D01*
G01X-96418Y582677D02*
G03X-92481Y586615I0J3937D01*
G01X-96418Y582677D02*
G03X-92481Y586615I0J3937D01*
G01X-96418Y574803D02*
G03X-84607Y586615I0J11811D01*
G01Y632284D02*
Y586615D01*
G01X-92481D02*
Y708662D01*
G01Y586615D02*
Y708662D01*
G01Y662992D02*
G03X-84607I3937J0D01*
G01Y632284D02*
G03X-92481I-3937J0D01*
G01X-84607Y708662D02*
Y662992D01*
G01X-92481D02*
Y632284D01*
G01Y708662D02*
G03X-96418Y712599I-3937J0D01*
G01X-92481Y708662D02*
G03X-96418Y712599I-3937J0D01*
G01X-84607Y708662D02*
G03X-96418Y720473I-11811J0D01*
G01X-11811Y-3937D02*
G03X-7874Y-7874I3937J0D01*
G01X31496D02*
X-7874D01*
G01X0Y3937D02*
G03X3937Y0I3937J0D01*
G01X0Y3937D02*
G03X3937Y0I3937J0D01*
G01X0Y3937D02*
Y208662D01*
G01X-11811Y-3937D02*
Y200788D01*
G01X755905Y0D02*
X3937D01*
G01X755905D02*
X3937D01*
G01X-11811Y200788D02*
G03X-15748Y204725I-3937J0D01*
G01X0Y208662D02*
G03X-3937Y212599I-3937J0D01*
G01X0Y208662D02*
G03X-3937Y212599I-3937J0D01*
G01X-59055Y503937D02*
Y346457D01*
G01Y503937D02*
Y346457D01*
G01Y488189D02*
Y457481D01*
G01X-23622Y552559D02*
G03X-27559Y548622I0J-3937D01*
G01X-11811Y552559D02*
G03X-7874Y556496I0J3937D01*
G01X-3937Y507874D02*
G03X0Y511811I0J3937D01*
G01X-3937Y507874D02*
G03X0Y511811I0J3937D01*
G01X-55118Y507874D02*
G03X-59055Y503937I0J-3937D01*
G01X-31496Y515748D02*
G03X-27559Y519685I0J3937D01*
G01X-55118Y507874D02*
G03X-59055Y503937I0J-3937D01*
G01X-23622Y552559D02*
X-11811D01*
G01X0Y511811D02*
Y783465D01*
G01X-27559Y519685D02*
Y548622D01*
G01X-55118Y515748D02*
X-31496D01*
G01X-3937Y507874D02*
X-55118D01*
G01X-3937D02*
X-55118D01*
G01X-7874Y556496D02*
Y783465D01*
G01X3937Y787402D02*
G03X0Y783465I0J-3937D01*
G01X3937Y787402D02*
G03X0Y783465I0J-3937D01*
G01X3937Y795276D02*
G03X-7874Y783465I0J-11811D01*
G01X3937Y795276D02*
X8661D01*
G01X3937Y787402D02*
X74803D01*
G01X3937D02*
X74803D01*
G01X51772Y-235263D02*
Y-252763D01*
X60506D01*
G01X68836Y-235263D02*
Y-247805D01*
X69709Y-250430D01*
X71456Y-252180D01*
X73639Y-252763D01*
X75822Y-252180D01*
X77569Y-250430D01*
X78442Y-247805D01*
Y-235263D01*
G01X95942Y-236722D02*
X94632Y-235846D01*
X93104Y-235263D01*
X91357D01*
X89392Y-236138D01*
X87864Y-237596D01*
X86772Y-239347D01*
X85899Y-242263D01*
X85680Y-244888D01*
X86117Y-247513D01*
X86772Y-249263D01*
X88082Y-251013D01*
X89611Y-252180D01*
X91139Y-252763D01*
X92667D01*
X94196Y-252180D01*
X95506Y-251305D01*
X96598Y-250139D01*
G01X103836Y-252763D02*
Y-235263D01*
G01X112132D02*
X103836Y-246055D01*
G01X113442Y-252763D02*
X107547Y-241097D01*
G01X126139Y-252763D02*
Y-244888D01*
X121772Y-235263D01*
G01X130506D02*
X126139Y-244888D01*
G01X25086Y-207763D02*
Y-190263D01*
X29452D01*
X31199Y-191138D01*
X32509Y-192305D01*
X33601Y-194054D01*
X34474Y-196097D01*
X34692Y-199013D01*
X34474Y-201930D01*
X33601Y-203972D01*
X32509Y-205722D01*
X31199Y-206888D01*
X29452Y-207763D01*
X25086D01*
G01X44114Y-199888D02*
X51101D01*
X50446Y-197846D01*
X49354Y-196680D01*
X47826Y-196097D01*
X46297Y-196388D01*
X44987Y-197263D01*
X44114Y-199305D01*
X43677Y-201055D01*
Y-202805D01*
X44114Y-204555D01*
X45206Y-206305D01*
X46516Y-207471D01*
X48044Y-207763D01*
X49572Y-207180D01*
X51101Y-205430D01*
G01X61614Y-205722D02*
X62706Y-206888D01*
X64234Y-207763D01*
X65544D01*
X66854Y-207180D01*
X67727Y-206305D01*
X68164Y-205139D01*
X67946Y-203388D01*
X67072Y-202513D01*
X63142Y-200763D01*
X62269Y-198721D01*
X62706Y-197263D01*
X63579Y-196388D01*
X64889Y-196097D01*
X66199Y-196388D01*
X67509Y-197263D01*
G01X82389Y-196097D02*
Y-207763D01*
G01Y-191430D02*
X81952Y-191138D01*
Y-190555D01*
X82389Y-190263D01*
X82826Y-190555D01*
Y-191138D01*
X82389Y-191430D01*
G01X96832Y-212138D02*
X98361Y-213305D01*
X100107Y-213596D01*
X101635Y-213305D01*
X102946Y-211847D01*
X103819Y-209805D01*
Y-196097D01*
G01Y-198430D02*
X102946Y-197263D01*
X101635Y-196388D01*
X100107Y-196097D01*
X98361Y-196680D01*
X97269Y-197846D01*
X96395Y-199888D01*
X95959Y-201930D01*
X96177Y-203680D01*
X97051Y-205722D01*
X98361Y-207180D01*
X100107Y-207763D01*
X101417Y-207471D01*
X102946Y-206305D01*
X103819Y-205139D01*
G01X113677Y-207763D02*
Y-196097D01*
G01Y-199013D02*
X114551Y-197555D01*
X115861Y-196388D01*
X117607Y-196097D01*
X119135Y-196388D01*
X120446Y-197555D01*
X121101Y-199596D01*
Y-207763D01*
G01X131614Y-199888D02*
X138601D01*
X137946Y-197846D01*
X136854Y-196680D01*
X135326Y-196097D01*
X133797Y-196388D01*
X132487Y-197263D01*
X131614Y-199305D01*
X131177Y-201055D01*
Y-202805D01*
X131614Y-204555D01*
X132706Y-206305D01*
X134016Y-207471D01*
X135544Y-207763D01*
X137072Y-207180D01*
X138601Y-205430D01*
G01X149332Y-207763D02*
Y-196097D01*
G01Y-198430D02*
X150424Y-197263D01*
X151516Y-196388D01*
X153044Y-196097D01*
X154135Y-196388D01*
X155446Y-197263D01*
G01X62204Y0D02*
G03Y-7874I0J-3937D01*
G01X31496D02*
G03Y0I0J3937D01*
G01X267716Y-7874D02*
X62204D01*
G01Y0D02*
X31496D01*
G01X74803Y787402D02*
G03X78740Y791339I0J3937D01*
G01X30315Y795276D02*
G03X34252Y799213I0J3937D01*
G01X24409Y795276D02*
G03Y787402I0J-3937D01*
G01X8661D02*
G03Y795276I0J3937D01*
G01X74803Y787402D02*
G03X78740Y791339I0J3937D01*
G01X24409Y795276D02*
X30315D01*
G01X24409Y787402D02*
X8661D01*
G01X34252Y799213D02*
Y889666D01*
G01X38189Y893603D02*
G03X34252Y889666I0J-3937D01*
G01X66929Y893603D02*
G03X70866Y897540I0J3937D01*
G01X38189Y893603D02*
X66929D01*
G01X70866Y897540D02*
Y929134D01*
G01X74803Y933071D02*
G03X70866Y929134I0J-3937D01*
G01X74803Y933071D02*
X88582D01*
G01X78740Y791339D02*
Y921260D01*
G01Y791339D02*
Y921260D01*
G01X119291Y933071D02*
G03Y925197I0J-3937D01*
G01X82677D02*
G03X78740Y921260I0J-3937D01*
G01X88582Y925197D02*
G03Y933071I0J3937D01*
G01X82677Y925197D02*
G03X78740Y921260I0J-3937D01*
G01X119291Y933071D02*
X305118D01*
G01X82677Y925197D02*
X755905D01*
G01X82677D02*
X755905D01*
G01X119291D02*
X88582D01*
G01X196089Y-252763D02*
Y-235263D01*
X193469Y-238763D01*
G01Y-252763D02*
X198709D01*
G01X213589Y-235263D02*
X211842Y-235846D01*
X210532Y-237305D01*
X209659Y-239054D01*
X209004Y-241388D01*
X208786Y-244013D01*
X209004Y-246638D01*
X209659Y-248972D01*
X210532Y-250722D01*
X211842Y-252180D01*
X213589Y-252763D01*
X215335Y-252180D01*
X216646Y-250722D01*
X217519Y-248972D01*
X218174Y-246638D01*
X218392Y-244013D01*
X218174Y-241388D01*
X217519Y-239054D01*
X216646Y-237305D01*
X215335Y-235846D01*
X213589Y-235263D01*
G01X227159Y-253346D02*
X235019Y-235263D01*
G01X248589Y-252763D02*
Y-235263D01*
X245969Y-238763D01*
G01Y-252763D02*
X251209D01*
G01X261941Y-245472D02*
X263469Y-243430D01*
X264779Y-242263D01*
X266526Y-241680D01*
X268054Y-242263D01*
X269146Y-243430D01*
X270019Y-245180D01*
X270237Y-247221D01*
X270019Y-248972D01*
X269146Y-250722D01*
X267835Y-252180D01*
X266307Y-252763D01*
X264561Y-252180D01*
X263032Y-250430D01*
X262159Y-247805D01*
X261941Y-244888D01*
X262377Y-241097D01*
X263032Y-239054D01*
X264124Y-237013D01*
X265652Y-235555D01*
X267181Y-235263D01*
X268709Y-235846D01*
X269801Y-237305D01*
G01X279659Y-253346D02*
X287519Y-235263D01*
G01X296941Y-238180D02*
X298251Y-236430D01*
X299779Y-235555D01*
X301526Y-235263D01*
X303709Y-235846D01*
X305237Y-237305D01*
X305674Y-239054D01*
X305456Y-240805D01*
X304582Y-242263D01*
X300216Y-245180D01*
X298251Y-247221D01*
X296941Y-250139D01*
X296504Y-252763D01*
X305674D01*
G01X318589Y-235263D02*
X316842Y-235846D01*
X315532Y-237305D01*
X314659Y-239054D01*
X314004Y-241388D01*
X313786Y-244013D01*
X314004Y-246638D01*
X314659Y-248972D01*
X315532Y-250722D01*
X316842Y-252180D01*
X318589Y-252763D01*
X320335Y-252180D01*
X321646Y-250722D01*
X322519Y-248972D01*
X323174Y-246638D01*
X323392Y-244013D01*
X323174Y-241388D01*
X322519Y-239054D01*
X321646Y-237305D01*
X320335Y-235846D01*
X318589Y-235263D01*
G01X336089Y-252763D02*
Y-235263D01*
X333469Y-238763D01*
G01Y-252763D02*
X338709D01*
G01X349441Y-238180D02*
X350751Y-236430D01*
X352279Y-235555D01*
X354026Y-235263D01*
X356209Y-235846D01*
X357737Y-237305D01*
X358174Y-239054D01*
X357956Y-240805D01*
X357082Y-242263D01*
X352716Y-245180D01*
X350751Y-247221D01*
X349441Y-250139D01*
X349004Y-252763D01*
X358174D01*
G01X243786Y-207763D02*
Y-190263D01*
X248152D01*
X249899Y-191138D01*
X251209Y-192305D01*
X252301Y-194054D01*
X253174Y-196097D01*
X253392Y-199013D01*
X253174Y-201930D01*
X252301Y-203972D01*
X251209Y-205722D01*
X249899Y-206888D01*
X248152Y-207763D01*
X243786D01*
G01X270019D02*
Y-196097D01*
G01Y-198138D02*
X269146Y-196972D01*
X267835Y-196388D01*
X266307Y-196097D01*
X264779Y-196680D01*
X263469Y-197846D01*
X262595Y-199596D01*
X262159Y-201930D01*
X262595Y-204263D01*
X263469Y-206013D01*
X264779Y-207180D01*
X266307Y-207763D01*
X267835Y-207471D01*
X269146Y-206597D01*
X270019Y-205430D01*
G01X283589Y-190263D02*
Y-207763D01*
G01X280532Y-196097D02*
X286646D01*
G01X297814Y-199888D02*
X304801D01*
X304146Y-197846D01*
X303054Y-196680D01*
X301526Y-196097D01*
X299997Y-196388D01*
X298687Y-197263D01*
X297814Y-199305D01*
X297377Y-201055D01*
Y-202805D01*
X297814Y-204555D01*
X298906Y-206305D01*
X300216Y-207471D01*
X301744Y-207763D01*
X303272Y-207180D01*
X304801Y-205430D01*
G01X267716Y-7874D02*
G03Y0I0J3937D01*
G01X298425D02*
X267716D01*
G01X298425D02*
G03Y-7874I0J-3937D01*
G01X483071D02*
X298425D01*
G01X335827Y933071D02*
G03Y925197I0J-3937D01*
G01X305118D02*
G03Y933071I0J3937D01*
G01X335827D02*
X522441D01*
G01X335827Y925197D02*
X305118D01*
G01X483071Y-7874D02*
G03Y0I0J3937D01*
G01X513779D02*
X483071D01*
G01X513779D02*
G03Y-7874I0J-3937D01*
G01X719291D02*
X513779D01*
G01X553149Y933071D02*
G03Y925197I0J-3937D01*
G01X522441D02*
G03Y933071I0J3937D01*
G01X553149D02*
X719291D01*
G01X553149Y925197D02*
X522441D01*
G01X763779Y-7874D02*
G03X767716Y-3937I0J3937D01*
G01X719291Y-7874D02*
G03Y0I0J3937D01*
G01X750000D02*
G03Y-7874I0J-3937D01*
G01X763779D02*
X750000D01*
G01X755905Y0D02*
G03X759842Y3937I0J3937D01*
G01X755905Y0D02*
G03X759842Y3937I0J3937D01*
G01X767716Y185827D02*
Y-3937D01*
G01X759842Y3937D02*
Y324213D01*
G01X750000Y0D02*
X719291D01*
G01X767716Y185827D02*
G03X759842I-3937J0D01*
G01Y216536D02*
Y185827D01*
G01Y216536D02*
G03X767716I3937J0D01*
G01Y316339D02*
Y216536D01*
G01X771653Y320276D02*
G03X767716Y316339I0J-3937D01*
G01X763779Y328150D02*
G03X759842Y324213I0J-3937D01*
G01X793307Y328150D02*
X763779D01*
G01X791338Y320276D02*
X771653D01*
G01X765945Y379725D02*
G03Y372244I0J-3741D01*
G01X793307Y379725D02*
X765945D01*
G01X793307Y372244D02*
X765945D01*
G01X759842Y663977D02*
G03X763779Y660040I3937J0D01*
G01X759842Y663977D02*
Y733662D01*
G01X793307Y660040D02*
X763779D01*
G01Y737599D02*
G03X759842Y733662I0J-3937D01*
G01X793307Y737599D02*
X763779D01*
G01X765945Y789174D02*
G03Y781693I0J-3740D01*
G01X767716Y829331D02*
G03X771653Y825394I3937J0D01*
G01X759842Y821457D02*
G03X763779Y817520I3937J0D01*
G01X767716Y855118D02*
Y829331D01*
G01X759842Y921260D02*
Y821457D01*
G01X771653Y825394D02*
X791338D01*
G01X793307Y817520D02*
X763779D01*
G01X793307Y789174D02*
X765945D01*
G01X793307Y781693D02*
X765945D01*
G01X767716Y855118D02*
G03X759842I-3937J0D01*
G01Y885827D02*
G03X767716I3937J0D01*
G01Y929134D02*
Y885827D01*
G01X759842D02*
Y855118D01*
G01Y921260D02*
G03X755905Y925197I-3937J0D01*
G01X767716Y929134D02*
G03X763779Y933071I-3937J0D01*
G01X750000D02*
G03Y925197I0J-3937D01*
G01X719291D02*
G03Y933071I0J3937D01*
G01X759842Y921260D02*
G03X755905Y925197I-3937J0D01*
G01X750000Y933071D02*
X763779D01*
G01X750000Y925197D02*
X719291D01*
G01X791338Y-35433D02*
G03X795275Y-31496I0J3937D01*
G01D02*
Y316339D01*
G01D02*
G03X791338Y320276I-3937J0D01*
G01X795275Y370276D02*
Y330118D01*
G01D02*
X793307Y328150D01*
G01X795275Y658071D02*
Y381693D01*
G01D02*
X793307Y379725D01*
G01X795275Y370276D02*
X793307Y372244D01*
G01X795275Y658071D02*
X793307Y660040D01*
G01X795275Y779725D02*
Y739567D01*
G01D02*
X793307Y737599D01*
G01X791338Y825394D02*
G03X795275Y829331I0J3937D01*
G01D02*
Y956693D01*
G01Y815552D02*
Y791142D01*
G01Y815552D02*
X793307Y817520D01*
G01X795275Y779725D02*
X793307Y781693D01*
G01X795275Y791142D02*
X793307Y789174D01*
G01X795275Y956693D02*
G03X791338Y960630I-3937J0D01*
G54D34*
X43500Y540200D03*
X118263Y415283D03*
X126310Y465403D03*
X102643Y465497D03*
X680800Y534800D03*
X701500D03*
G54D43*
X102363Y454883D03*
X125579Y427173D03*
X701500Y524200D03*
X680800D03*
G54D25*
X63444Y266211D03*
X38892Y293747D03*
X130163Y413483D03*
X137163Y434483D03*
X129768Y422719D03*
X434994Y457361D03*
X435016Y449543D03*
G54D16*
X74800Y91200D03*
X43851Y182228D03*
X43794Y197158D03*
X22900Y313600D03*
X39236Y283887D03*
X27000Y313500D03*
X31100D03*
X63942Y537679D03*
X67065Y519137D03*
X98138Y405678D03*
X89163Y390283D03*
X94076Y414654D03*
X118163Y474383D03*
X149799Y452326D03*
X428616Y437029D03*
X684869Y438211D03*
X680738Y438233D03*
X693509Y438301D03*
X689111Y438212D03*
X705600Y554600D03*
X663300Y529600D03*
X648200Y555500D03*
X705927Y532127D03*
X668699Y556030D03*
X726040Y550596D03*
G54D44*
X172508Y238287D03*
X180108D03*
X680225Y486151D03*
X672625D03*
X679809Y478423D03*
X672209D03*
G54D26*
X63444Y262611D03*
X38892Y290147D03*
X130163Y409883D03*
X137163Y430883D03*
X129768Y419119D03*
X434994Y453761D03*
X435016Y445943D03*
G54D17*
X43848Y189691D03*
X30773Y274407D03*
X35107Y274462D03*
X67367Y526739D03*
X63918Y545213D03*
X113749Y313569D03*
X93263Y390283D03*
X107363Y450183D03*
X94500Y465600D03*
X91167Y491594D03*
X181278Y247657D03*
X424282Y437118D03*
X707109Y438423D03*
X698367Y438402D03*
X702508Y438404D03*
X705600Y547000D03*
X663300Y522000D03*
X648200Y548000D03*
X705928Y524645D03*
X668705Y548544D03*
X685815Y493278D03*
X689996Y493247D03*
X698475Y493274D03*
X694196Y493347D03*
X707296D03*
X702648Y493237D03*
X668743Y541065D03*
X726045Y543153D03*
G54D35*
X43500Y534600D03*
X118263Y409683D03*
X126310Y459803D03*
X102643Y459897D03*
X680800Y529200D03*
X701500D03*
G54D45*
X419225Y453324D03*
G54D18*
X43848Y186291D03*
X30773Y271007D03*
X35107Y271062D03*
X67367Y523339D03*
X63918Y541813D03*
X113749Y310169D03*
X93263Y386883D03*
X107363Y446783D03*
X94500Y462200D03*
X91167Y488194D03*
X181278Y244257D03*
X424282Y433718D03*
X707109Y435023D03*
X698367Y435002D03*
X702508Y435004D03*
X705600Y543600D03*
X663300Y518600D03*
X648200Y544600D03*
X705928Y521245D03*
X668705Y545144D03*
X685815Y489878D03*
X689996Y489847D03*
X698475Y489874D03*
X694196Y489947D03*
X707296D03*
X702648Y489837D03*
X668743Y537665D03*
X726045Y539753D03*
G54D36*
X62977Y500748D03*
G54D27*
X62358Y211203D03*
X57483Y385340D03*
X55073Y443238D03*
X48131Y476567D03*
X59963Y488683D03*
X51120Y530394D03*
X113763Y306003D03*
X89463Y397283D03*
X171155Y265687D03*
X171111Y261545D03*
X173700Y273900D03*
X173715Y244229D03*
X176608Y289824D03*
X233100Y482400D03*
Y486500D03*
Y478300D03*
Y474200D03*
X427649Y469469D03*
X686400Y545500D03*
X653367Y563931D03*
X693829Y766898D03*
X693807Y762804D03*
X693820Y838158D03*
X693779Y834000D03*
X693800Y829925D03*
X694630Y800492D03*
X694504Y796145D03*
X694293Y791967D03*
X693998Y787599D03*
X693955Y783400D03*
X693934Y779285D03*
X693913Y775149D03*
X693870Y771013D03*
X693947Y854741D03*
X693916Y850609D03*
X693887Y846395D03*
X693868Y842302D03*
X686310Y854661D03*
X726900Y535700D03*
X749500Y554700D03*
Y550600D03*
Y563300D03*
Y559200D03*
X738263Y855068D03*
G54D19*
X76300Y144900D03*
X62368Y198735D03*
X72706Y185541D03*
X62359Y202789D03*
X60200Y251200D03*
X62347Y206909D03*
X57483Y381140D03*
X70763Y386683D03*
X55507Y450659D03*
X55550Y455007D03*
X43473Y528179D03*
X83100Y225900D03*
X84550Y409763D03*
X89463Y401383D03*
X88564Y405439D03*
X176564Y294017D03*
X416638Y471346D03*
X416632Y475470D03*
X712245Y485000D03*
Y480900D03*
X693400Y511400D03*
X710826Y560695D03*
X693856Y825792D03*
X712900Y529600D03*
Y525500D03*
X737982Y850566D03*
X737962Y846447D03*
X738100Y859500D03*
G54D46*
X414107Y443581D03*
X416666D03*
X419225D03*
X421784D03*
X424343D03*
Y463067D03*
X421784D03*
X419225D03*
X416666D03*
X414107D03*
G54D37*
X57377Y500748D03*
G54D28*
X65758Y211203D03*
X60883Y385340D03*
X58473Y443238D03*
X51531Y476567D03*
X63363Y488683D03*
X54520Y530394D03*
X117163Y306003D03*
X92863Y397283D03*
X174555Y265687D03*
X174511Y261545D03*
X177100Y273900D03*
X177115Y244229D03*
X180008Y289824D03*
X236500Y482400D03*
Y486500D03*
Y478300D03*
Y474200D03*
X431049Y469469D03*
X689800Y545500D03*
X656767Y563931D03*
X697229Y766898D03*
X697207Y762804D03*
X697220Y838158D03*
X697179Y834000D03*
X697200Y829925D03*
X698030Y800492D03*
X697904Y796145D03*
X697693Y791967D03*
X697398Y787599D03*
X697355Y783400D03*
X697334Y779285D03*
X697313Y775149D03*
X697270Y771013D03*
X697347Y854741D03*
X697316Y850609D03*
X697287Y846395D03*
X697268Y842302D03*
X689710Y854661D03*
X730300Y535700D03*
X752900Y554700D03*
Y550600D03*
Y563300D03*
Y559200D03*
X741663Y855068D03*
G54D29*
X77963Y273483D03*
Y270923D03*
Y268363D03*
Y242773D03*
Y245333D03*
Y247888D03*
Y250448D03*
Y253008D03*
Y255568D03*
Y258128D03*
Y260683D03*
Y263243D03*
Y265803D03*
Y291393D03*
Y288833D03*
Y286278D03*
Y283718D03*
Y281158D03*
Y278598D03*
Y276038D03*
X161963Y242773D03*
Y245333D03*
Y247888D03*
Y250448D03*
Y253008D03*
Y255568D03*
Y258128D03*
Y260683D03*
Y263243D03*
Y265803D03*
Y273483D03*
Y270923D03*
Y268363D03*
Y291393D03*
Y288833D03*
Y286278D03*
Y283718D03*
Y281158D03*
Y278598D03*
Y276038D03*
G54D38*
X60403Y524823D03*
Y517073D03*
X52903Y520948D03*
X57065Y544023D03*
Y536273D03*
X49565Y540148D03*
G54D47*
X428968Y448206D03*
Y450765D03*
Y453324D03*
Y455883D03*
Y458442D03*
X409482D03*
Y455883D03*
Y453324D03*
Y450765D03*
Y448206D03*
G54D48*
X691905Y448220D03*
X693874D03*
X695842D03*
X697811D03*
Y483820D03*
X695842D03*
X693874D03*
X691905D03*
G54D39*
X62000Y609872D03*
Y605972D03*
X62100Y600272D03*
Y596372D03*
Y576887D03*
Y572987D03*
X62200Y567387D03*
Y563487D03*
X62651Y694403D03*
Y690503D03*
Y684703D03*
Y680803D03*
X61600Y728513D03*
Y724613D03*
X61700Y718613D03*
Y714713D03*
X131100Y228600D03*
X90763Y228783D03*
X90819Y305456D03*
X121263Y305503D03*
X131963Y305603D03*
X106805Y413570D03*
X114863Y421283D03*
X120963Y441583D03*
X121763Y449983D03*
X113363Y441583D03*
X109463Y434383D03*
X136163Y441583D03*
X129663Y449183D03*
X119263Y433683D03*
X126983Y434871D03*
Y431371D03*
X129663Y452683D03*
X171696Y269694D03*
X168269Y432425D03*
X157063Y440683D03*
X150640Y837095D03*
X150751Y832781D03*
Y828981D03*
X152236Y817740D03*
Y814140D03*
X151488Y853750D03*
X151561Y850210D03*
X150440Y840895D03*
X707930Y464221D03*
X708009Y453723D03*
X653700Y533400D03*
G54D49*
X701858Y450272D03*
Y452240D03*
Y454209D03*
Y456177D03*
Y458146D03*
Y460114D03*
Y462083D03*
Y464051D03*
Y466020D03*
Y467989D03*
Y469957D03*
Y471926D03*
Y473894D03*
Y475863D03*
Y477831D03*
Y479800D03*
Y481768D03*
X687858D03*
Y479800D03*
Y477831D03*
Y475863D03*
Y473894D03*
Y471926D03*
Y469957D03*
Y467989D03*
Y466020D03*
Y464051D03*
Y462083D03*
Y460114D03*
Y458146D03*
Y456177D03*
Y454209D03*
Y452240D03*
Y450272D03*
M02*
